(kicad_pcb
	(version 20260206)
	(generator "pcbnew")
	(generator_version "10.0")
	(general
		(thickness 1.6)
		(legacy_teardrops no)
	)
	(paper "A4")
	(title_block
		(title "timecard-production-celestica-r4006 — R4006-B0001-02_R01.brd")
		(comment 1 "Time Appliance Project (Time Card) / footprints 588-589 of 1113")
	)
	(layers
		(0 "F.Cu" signal "TOP")
		(4 "In1.Cu" signal "L02_GND1")
		(6 "In2.Cu" signal "L03_SIG1")
		(8 "In3.Cu" signal "L04_GND2")
		(10 "In4.Cu" signal "L05_VCC1")
		(12 "In5.Cu" signal "L06_VCC2")
		(14 "In6.Cu" signal "L07_GND3")
		(16 "In7.Cu" signal "L08_SIG2")
		(18 "In8.Cu" signal "L09_GND4")
		(2 "B.Cu" signal "BOTTOM")
		(9 "F.Adhes" user "F.Adhesive")
		(11 "B.Adhes" user "B.Adhesive")
		(13 "F.Paste" user "Package Geometry/Pastemask Top")
		(15 "B.Paste" user "Package Geometry/Pastemask Bottom")
		(5 "F.SilkS" user "Ref Des/Silkscreen Top")
		(7 "B.SilkS" user "Ref Des/Silkscreen Bottom")
		(1 "F.Mask" user "Board Geometry/Soldermask Top")
		(3 "B.Mask" user "Board Geometry/Soldermask Bottom")
		(17 "Dwgs.User" user "User.Drawings")
		(19 "Cmts.User" user "User.Comments")
		(21 "Eco1.User" user "User.Eco1")
		(23 "Eco2.User" user "User.Eco2")
		(25 "Edge.Cuts" user "Board Geometry/Outline")
		(27 "Margin" user)
		(31 "F.CrtYd" user "Package Geometry/Place Bound Top")
		(29 "B.CrtYd" user "Package Geometry/Place Bound Bottom")
		(35 "F.Fab" user "Ref Des/Assembly Top")
		(33 "B.Fab" user "Ref Des/Assembly Bottom")
	)
	(footprint ""
		(layer "F.Cu")
		(at 89.9922 -102.4128)
		(property "Reference" "C46"
			(at 3.048 0.16637 0)
			(unlocked yes)
			(layer "F.SilkS")
			(effects
				(font
					(size 0.7874 0.5842)
					(thickness 0.1524)
				)
			)
		)
		(property "Value" "VAL*"
			(at 0.0762 2.067306 0)
			(unlocked yes)
			(layer "F.Fab")
			(hide yes)
			(effects
				(font
					(size 0.7874 0.5842)
					(thickness 0.1524)
				)
			)
		)
		(property "Tolerance" "TOL*"
			(at 0.0762 3.032506 0)
			(unlocked yes)
			(layer "Cmts.User")
			(hide yes)
			(effects
				(font
					(size 0.7874 0.5842)
					(thickness 0.1524)
				)
			)
		)
		(property "User Part Number" "PARTNUM*"
			(at 0.1016 4.023106 0)
			(unlocked yes)
			(layer "Cmts.User")
			(hide yes)
			(effects
				(font
					(size 0.7874 0.5842)
					(thickness 0.1524)
				)
			)
		)
		(property "Device Type" "CAPACITOR-G105-0B104-CK,0.1UF,A"
			(at 0.0508 1.127506 0)
			(unlocked yes)
			(layer "F.Fab")
			(hide yes)
			(effects
				(font
					(size 0.7874 0.5842)
					(thickness 0.1524)
				)
			)
		)
		(duplicate_pad_numbers_are_jumpers no)
		(fp_line
			(start -1.143 -0.5588)
			(end -1.143 0.5588)
			(stroke
				(width 0.1)
				(type default)
			)
			(layer "F.SilkS")
		)
		(fp_line
			(start -1.143 0.5588)
			(end 1.143 0.5588)
			(stroke
				(width 0.1)
				(type default)
			)
			(layer "F.SilkS")
		)
		(fp_line
			(start 1.143 -0.5588)
			(end -1.143 -0.5588)
			(stroke
				(width 0.1)
				(type default)
			)
			(layer "F.SilkS")
		)
		(fp_line
			(start 1.143 0.5588)
			(end 1.143 -0.5588)
			(stroke
				(width 0.1)
				(type default)
			)
			(layer "F.SilkS")
		)
		(fp_rect
			(start -1.143 0.5588)
			(end 1.143 -0.5588)
			(stroke
				(width 0)
				(type default)
			)
			(fill no)
			(layer "F.CrtYd")
		)
		(fp_line
			(start -0.508 -0.3048)
			(end -0.508 0.3048)
			(stroke
				(width 0.1)
				(type default)
			)
			(layer "F.Fab")
		)
		(fp_line
			(start -0.508 0.3048)
			(end 0.508 0.3048)
			(stroke
				(width 0.1)
				(type default)
			)
			(layer "F.Fab")
		)
		(fp_line
			(start 0.508 -0.3048)
			(end -0.508 -0.3048)
			(stroke
				(width 0.1)
				(type default)
			)
			(layer "F.Fab")
		)
		(fp_line
			(start 0.508 0.3048)
			(end 0.508 -0.3048)
			(stroke
				(width 0.1)
				(type default)
			)
			(layer "F.Fab")
		)
		(pad "1" smd rect
			(at -0.5334 0)
			(size 0.7112 0.6096)
			(layers "F.Cu" "F.Mask" "F.Paste")
			(net "XP3R3V_EN")
		)
		(pad "2" smd rect
			(at 0.5334 0)
			(size 0.7112 0.6096)
			(layers "F.Cu" "F.Mask" "F.Paste")
			(net "SG")
		)
		(zone
			(layer "F.Cu")
			(hatch none 0.5)
			(connect_pads
				(clearance 0)
			)
			(min_thickness 0.25)
			(keepout
				(tracks allowed)
				(vias not_allowed)
				(pads allowed)
				(copperpour not_allowed)
				(footprints allowed)
			)
			(placement
				(enabled no)
				(sheetname "")
			)
			(fill
				(thermal_gap 0.5)
				(thermal_bridge_width 0.5)
				(island_removal_mode 0)
			)
			(polygon
				(pts
					(xy 89.916 -102.108) (xy 90.0684 -102.108) (xy 90.0684 -102.7176) (xy 89.916 -102.7176)
				)
			)
		)
	)
	(footprint ""
		(layer "F.Cu")
		(at 79.8576 -44.45 180)
		(property "Reference" "R88"
			(at -0.0254 -14.00937 0)
			(unlocked yes)
			(layer "F.SilkS")
			(effects
				(font
					(size 0.7874 0.5842)
					(thickness 0.1524)
				)
			)
		)
		(property "Value" "VAL*"
			(at 0.02032 2.13233 180)
			(unlocked yes)
			(layer "F.Fab")
			(hide yes)
			(effects
				(font
					(size 0.7874 0.5842)
					(thickness 0.1524)
				)
			)
		)
		(property "Device Type" "RESISTOR-G155-100R0-J0,0OHM,-"
			(at 0.008382 1.210564 180)
			(unlocked yes)
			(layer "F.Fab")
			(hide yes)
			(effects
				(font
					(size 0.7874 0.5842)
					(thickness 0.1524)
				)
			)
		)
		(property "User Part Number" "PARTNUM*"
			(at 0.02032 4.024884 180)
			(unlocked yes)
			(layer "Cmts.User")
			(hide yes)
			(effects
				(font
					(size 0.7874 0.5842)
					(thickness 0.1524)
				)
			)
		)
		(property "Tolerance" "TOL*"
			(at 0.044704 3.05435 180)
			(unlocked yes)
			(layer "Cmts.User")
			(hide yes)
			(effects
				(font
					(size 0.7874 0.5842)
					(thickness 0.1524)
				)
			)
		)
		(duplicate_pad_numbers_are_jumpers no)
		(fp_line
			(start 1.143 0.5588)
			(end 1.143 -0.5588)
			(stroke
				(width 0.1)
				(type default)
			)
			(layer "F.SilkS")
		)
		(fp_line
			(start 1.143 -0.5588)
			(end -1.143 -0.5588)
			(stroke
				(width 0.1)
				(type default)
			)
			(layer "F.SilkS")
		)
		(fp_line
			(start -1.143 0.5588)
			(end 1.143 0.5588)
			(stroke
				(width 0.1)
				(type default)
			)
			(layer "F.SilkS")
		)
		(fp_line
			(start -1.143 -0.5588)
			(end -1.143 0.5588)
			(stroke
				(width 0.1)
				(type default)
			)
			(layer "F.SilkS")
		)
		(fp_rect
			(start 1.143 -0.5588)
			(end -1.143 0.5588)
			(stroke
				(width 0)
				(type default)
			)
			(fill no)
			(layer "F.CrtYd")
		)
		(fp_line
			(start 0.508 0.3048)
			(end 0.508 -0.3048)
			(stroke
				(width 0.1)
				(type default)
			)
			(layer "F.Fab")
		)
		(fp_line
			(start 0.508 -0.3048)
			(end -0.508 -0.3048)
			(stroke
				(width 0.1)
				(type default)
			)
			(layer "F.Fab")
		)
		(fp_line
			(start -0.508 0.3048)
			(end 0.508 0.3048)
			(stroke
				(width 0.1)
				(type default)
			)
			(layer "F.Fab")
		)
		(fp_line
			(start -0.508 -0.3048)
			(end -0.508 0.3048)
			(stroke
				(width 0.1)
				(type default)
			)
			(layer "F.Fab")
		)
		(pad "1" smd rect
			(at -0.5334 0 180)
			(size 0.7112 0.6096)
			(layers "F.Cu" "F.Mask" "F.Paste")
			(net "FPGA_IN_MAC_PPS_OUTN")
		)
		(pad "2" smd rect
			(at 0.5334 0 180)
			(size 0.7112 0.6096)
			(layers "F.Cu" "F.Mask" "F.Paste")
			(net "R_MAC_PPS_OUTN")
		)
		(zone
			(layer "F.Cu")
			(hatch none 0.5)
			(connect_pads
				(clearance 0)
			)
			(min_thickness 0.25)
			(keepout
				(tracks allowed)
				(vias not_allowed)
				(pads allowed)
				(copperpour not_allowed)
				(footprints allowed)
			)
			(placement
				(enabled no)
				(sheetname "")
			)
			(fill
				(thermal_gap 0.5)
				(thermal_bridge_width 0.5)
				(island_removal_mode 0)
			)
			(polygon
				(pts
					(xy 79.7814 -44.1452) (xy 79.9338 -44.1452) (xy 79.9338 -44.7548) (xy 79.7814 -44.7548)
				)
			)
		)
	)
)
